(kicad_pcb
	(version 20260206)
	(generator "pcbnew")
	(generator_version "10.0")
	(general
		(thickness 1.6)
		(legacy_teardrops no)
	)
	(paper "A4")
	(title_block
		(title "01162023_DA0F0TEBIF0_F0T_Expander_BD_F_brd_V02_OCP.brd")
		(comment 1 "Grand Teton / footprints 8672-8679 of 9728")
	)
	(layers
		(0 "F.Cu" signal "TOP")
		(4 "In1.Cu" signal "GND")
		(6 "In2.Cu" signal "VCC")
		(8 "In3.Cu" signal "VCC1")
		(10 "In4.Cu" signal "GND1")
		(12 "In5.Cu" signal "IN1")
		(14 "In6.Cu" signal "GND2")
		(16 "In7.Cu" signal "IN2")
		(18 "In8.Cu" signal "GND3")
		(20 "In9.Cu" signal "IN3")
		(22 "In10.Cu" signal "GND4")
		(24 "In11.Cu" signal "IN4")
		(26 "In12.Cu" signal "GND5")
		(28 "In13.Cu" signal "IN5")
		(30 "In14.Cu" signal "GND6")
		(32 "In15.Cu" signal "IN6")
		(34 "In16.Cu" signal "GND7")
		(2 "B.Cu" signal "BOTTOM")
		(9 "F.Adhes" user "F.Adhesive")
		(11 "B.Adhes" user "B.Adhesive")
		(13 "F.Paste" user "Package Geometry/Pastemask Top")
		(15 "B.Paste" user "Package Geometry/Pastemask Bottom")
		(5 "F.SilkS" user "Ref Des/Silkscreen Top")
		(7 "B.SilkS" user "Ref Des/Silkscreen Bottom")
		(1 "F.Mask" user "Board Geometry/Soldermask Top")
		(3 "B.Mask" user "Board Geometry/Soldermask Bottom")
		(17 "Dwgs.User" user "User.Drawings")
		(19 "Cmts.User" user "User.Comments")
		(21 "Eco1.User" user "User.Eco1")
		(23 "Eco2.User" user "User.Eco2")
		(25 "Edge.Cuts" user "Board Geometry/Outline")
		(27 "Margin" user)
		(31 "F.CrtYd" user "Package Geometry/Place Bound Top")
		(29 "B.CrtYd" user "Package Geometry/Place Bound Bottom")
		(35 "F.Fab" user "Ref Des/Assembly Top")
		(33 "B.Fab" user "Ref Des/Assembly Bottom")
	)
	(footprint ""
		(layer "B.Cu")
		(at 338.893912 -216.386918 90)
		(property "Reference" "C2076"
			(at 0 0 90)
			(layer "B.SilkS")
			(hide yes)
			(effects
				(font
					(size 1.27 1.27)
				)
				(justify mirror)
			)
		)
		(property "Value" ""
			(at 0 0 90)
			(layer "B.Fab")
			(effects
				(font
					(size 1.27 1.27)
				)
				(justify mirror)
			)
		)
		(duplicate_pad_numbers_are_jumpers no)
		(fp_line
			(start 0.69215 -0.2921)
			(end -0.69215 -0.2921)
			(stroke
				(width 0.1524)
				(type default)
			)
			(layer "B.SilkS")
		)
		(fp_line
			(start -0.69215 -0.2921)
			(end -0.69215 0.2921)
			(stroke
				(width 0.1524)
				(type default)
			)
			(layer "B.SilkS")
		)
		(fp_line
			(start 0.69215 0.2921)
			(end 0.69215 -0.2921)
			(stroke
				(width 0.1524)
				(type default)
			)
			(layer "B.SilkS")
		)
		(fp_line
			(start -0.69215 0.2921)
			(end 0.69215 0.2921)
			(stroke
				(width 0.1524)
				(type default)
			)
			(layer "B.SilkS")
		)
		(fp_line
			(start 0.51435 -0.2794)
			(end -0.51435 -0.2794)
			(stroke
				(width 0.1)
				(type default)
			)
			(layer "B.Fab")
		)
		(fp_line
			(start -0.51435 -0.2794)
			(end -0.51435 0.2794)
			(stroke
				(width 0.1)
				(type default)
			)
			(layer "B.Fab")
		)
		(fp_line
			(start 0.51435 0.2794)
			(end 0.51435 -0.2794)
			(stroke
				(width 0.1)
				(type default)
			)
			(layer "B.Fab")
		)
		(fp_line
			(start -0.51435 0.2794)
			(end 0.51435 0.2794)
			(stroke
				(width 0.1)
				(type default)
			)
			(layer "B.Fab")
		)
		(pad "1" smd circle
			(at 0.40005 0 270)
			(size 0 0)
			(layers "B.Cu" "B.Mask" "B.Paste")
			(net "P3V3_FPGA_VCCIO3")
		)
		(pad "2" smd circle
			(at -0.40005 0 270)
			(size 0 0)
			(layers "B.Cu" "B.Mask" "B.Paste")
			(net "GND")
		)
		(zone
			(layer "B.Cu")
			(hatch none 0.5)
			(connect_pads
				(clearance 0)
			)
			(min_thickness 0.25)
			(keepout
				(tracks not_allowed)
				(vias allowed)
				(pads allowed)
				(copperpour not_allowed)
				(footprints allowed)
			)
			(placement
				(enabled no)
				(sheetname "")
			)
			(fill
				(thermal_gap 0.5)
				(thermal_bridge_width 0.5)
				(island_removal_mode 0)
			)
			(polygon
				(pts
					(xy 338.981542 -216.577418) (xy 339.039708 -216.485978) (xy 339.039708 -216.286588) (xy 338.981542 -216.196418)
					(xy 338.806282 -216.196418) (xy 338.747862 -216.286588) (xy 338.747862 -216.485978) (xy 338.806028 -216.577418)
				)
			)
		)
	)
	(footprint ""
		(layer "B.Cu")
		(at 214.432642 -222.370904 180)
		(property "Reference" "R1489"
			(at 0 0 0)
			(layer "B.SilkS")
			(hide yes)
			(effects
				(font
					(size 1.27 1.27)
				)
				(justify mirror)
			)
		)
		(property "Value" ""
			(at 0 0 0)
			(layer "B.Fab")
			(effects
				(font
					(size 1.27 1.27)
				)
				(justify mirror)
			)
		)
		(duplicate_pad_numbers_are_jumpers no)
		(fp_line
			(start 0.7874 0.4064)
			(end 0.7874 -0.4064)
			(stroke
				(width 0.1524)
				(type default)
			)
			(layer "B.SilkS")
		)
		(fp_line
			(start 0.7874 -0.4064)
			(end -0.7874 -0.4064)
			(stroke
				(width 0.1524)
				(type default)
			)
			(layer "B.SilkS")
		)
		(fp_line
			(start -0.7874 0.4064)
			(end 0.7874 0.4064)
			(stroke
				(width 0.1524)
				(type default)
			)
			(layer "B.SilkS")
		)
		(fp_line
			(start -0.7874 -0.4064)
			(end -0.7874 0.4064)
			(stroke
				(width 0.1524)
				(type default)
			)
			(layer "B.SilkS")
		)
		(fp_line
			(start 0.67945 0.3048)
			(end 0.67945 -0.305054)
			(stroke
				(width 0.1)
				(type default)
			)
			(layer "B.Fab")
		)
		(fp_line
			(start 0.67945 -0.305054)
			(end 0.12065 -0.305054)
			(stroke
				(width 0.1)
				(type default)
			)
			(layer "B.Fab")
		)
		(fp_line
			(start 0.12065 0.3048)
			(end 0.67945 0.3048)
			(stroke
				(width 0.1)
				(type default)
			)
			(layer "B.Fab")
		)
		(fp_line
			(start 0.12065 0.2794)
			(end 0.12065 0.3048)
			(stroke
				(width 0.1)
				(type default)
			)
			(layer "B.Fab")
		)
		(fp_line
			(start 0.12065 -0.2794)
			(end -0.12065 -0.2794)
			(stroke
				(width 0.1)
				(type default)
			)
			(layer "B.Fab")
		)
		(fp_line
			(start 0.12065 -0.305054)
			(end 0.12065 -0.2794)
			(stroke
				(width 0.1)
				(type default)
			)
			(layer "B.Fab")
		)
		(fp_line
			(start -0.120396 0.3048)
			(end -0.120396 0.2794)
			(stroke
				(width 0.1)
				(type default)
			)
			(layer "B.Fab")
		)
		(fp_line
			(start -0.120396 0.2794)
			(end 0.12065 0.2794)
			(stroke
				(width 0.1)
				(type default)
			)
			(layer "B.Fab")
		)
		(fp_line
			(start -0.12065 -0.2794)
			(end -0.12065 -0.3048)
			(stroke
				(width 0.1)
				(type default)
			)
			(layer "B.Fab")
		)
		(fp_line
			(start -0.12065 -0.3048)
			(end -0.67945 -0.3048)
			(stroke
				(width 0.1)
				(type default)
			)
			(layer "B.Fab")
		)
		(fp_line
			(start -0.67945 0.3048)
			(end -0.120396 0.3048)
			(stroke
				(width 0.1)
				(type default)
			)
			(layer "B.Fab")
		)
		(fp_line
			(start -0.67945 -0.3048)
			(end -0.67945 0.3048)
			(stroke
				(width 0.1)
				(type default)
			)
			(layer "B.Fab")
		)
		(pad "1" smd circle
			(at 0.40005 0)
			(size 0 0)
			(layers "B.Cu" "B.Mask" "B.Paste")
			(net "SMB_BIC_FPGA_SDA")
		)
		(pad "2" smd circle
			(at -0.40005 0)
			(size 0 0)
			(layers "B.Cu" "B.Mask" "B.Paste")
			(net "SMB_BIC_FPGA_R_SDA")
		)
	)
	(footprint ""
		(layer "B.Cu")
		(at 304.728626 -242.262406)
		(property "Reference" "C2779"
			(at 0 0 0)
			(layer "B.SilkS")
			(hide yes)
			(effects
				(font
					(size 1.27 1.27)
				)
				(justify mirror)
			)
		)
		(property "Value" ""
			(at 0 0 0)
			(layer "B.Fab")
			(effects
				(font
					(size 1.27 1.27)
				)
				(justify mirror)
			)
		)
		(duplicate_pad_numbers_are_jumpers no)
		(fp_line
			(start -0.7874 -0.4064)
			(end -0.7874 0.4064)
			(stroke
				(width 0.1524)
				(type default)
			)
			(layer "B.SilkS")
		)
		(fp_line
			(start -0.7874 0.4064)
			(end 0.7874 0.4064)
			(stroke
				(width 0.1524)
				(type default)
			)
			(layer "B.SilkS")
		)
		(fp_line
			(start 0.7874 -0.4064)
			(end -0.7874 -0.4064)
			(stroke
				(width 0.1524)
				(type default)
			)
			(layer "B.SilkS")
		)
		(fp_line
			(start 0.7874 0.4064)
			(end 0.7874 -0.4064)
			(stroke
				(width 0.1524)
				(type default)
			)
			(layer "B.SilkS")
		)
		(fp_line
			(start -0.67945 -0.3048)
			(end -0.67945 0.3048)
			(stroke
				(width 0.1)
				(type default)
			)
			(layer "B.Fab")
		)
		(fp_line
			(start -0.67945 0.3048)
			(end -0.120396 0.3048)
			(stroke
				(width 0.1)
				(type default)
			)
			(layer "B.Fab")
		)
		(fp_line
			(start -0.12065 -0.3048)
			(end -0.67945 -0.3048)
			(stroke
				(width 0.1)
				(type default)
			)
			(layer "B.Fab")
		)
		(fp_line
			(start -0.12065 -0.2794)
			(end -0.12065 -0.3048)
			(stroke
				(width 0.1)
				(type default)
			)
			(layer "B.Fab")
		)
		(fp_line
			(start -0.120396 0.2794)
			(end 0.12065 0.2794)
			(stroke
				(width 0.1)
				(type default)
			)
			(layer "B.Fab")
		)
		(fp_line
			(start -0.120396 0.3048)
			(end -0.120396 0.2794)
			(stroke
				(width 0.1)
				(type default)
			)
			(layer "B.Fab")
		)
		(fp_line
			(start 0.12065 -0.305054)
			(end 0.12065 -0.2794)
			(stroke
				(width 0.1)
				(type default)
			)
			(layer "B.Fab")
		)
		(fp_line
			(start 0.12065 -0.2794)
			(end -0.12065 -0.2794)
			(stroke
				(width 0.1)
				(type default)
			)
			(layer "B.Fab")
		)
		(fp_line
			(start 0.12065 0.2794)
			(end 0.12065 0.3048)
			(stroke
				(width 0.1)
				(type default)
			)
			(layer "B.Fab")
		)
		(fp_line
			(start 0.12065 0.3048)
			(end 0.67945 0.3048)
			(stroke
				(width 0.1)
				(type default)
			)
			(layer "B.Fab")
		)
		(fp_line
			(start 0.67945 -0.305054)
			(end 0.12065 -0.305054)
			(stroke
				(width 0.1)
				(type default)
			)
			(layer "B.Fab")
		)
		(fp_line
			(start 0.67945 0.3048)
			(end 0.67945 -0.305054)
			(stroke
				(width 0.1)
				(type default)
			)
			(layer "B.Fab")
		)
		(pad "1" smd circle
			(at 0.40005 0 180)
			(size 0 0)
			(layers "B.Cu" "B.Mask" "B.Paste")
			(net "GND")
		)
		(pad "2" smd circle
			(at -0.40005 0 180)
			(size 0 0)
			(layers "B.Cu" "B.Mask" "B.Paste")
			(net "P3V3_AUX")
		)
	)
	(footprint ""
		(layer "B.Cu")
		(at 108.059982 -282.168092 90)
		(property "Reference" "R6762"
			(at 0 0 90)
			(layer "B.SilkS")
			(hide yes)
			(effects
				(font
					(size 1.27 1.27)
				)
				(justify mirror)
			)
		)
		(property "Value" ""
			(at 0 0 90)
			(layer "B.Fab")
			(effects
				(font
					(size 1.27 1.27)
				)
				(justify mirror)
			)
		)
		(duplicate_pad_numbers_are_jumpers no)
		(fp_line
			(start 0.7874 -0.4064)
			(end -0.7874 -0.4064)
			(stroke
				(width 0.1524)
				(type default)
			)
			(layer "B.SilkS")
		)
		(fp_line
			(start -0.7874 -0.4064)
			(end -0.7874 0.4064)
			(stroke
				(width 0.1524)
				(type default)
			)
			(layer "B.SilkS")
		)
		(fp_line
			(start 0.7874 0.4064)
			(end 0.7874 -0.4064)
			(stroke
				(width 0.1524)
				(type default)
			)
			(layer "B.SilkS")
		)
		(fp_line
			(start -0.7874 0.4064)
			(end 0.7874 0.4064)
			(stroke
				(width 0.1524)
				(type default)
			)
			(layer "B.SilkS")
		)
		(fp_line
			(start 0.67945 -0.305054)
			(end 0.12065 -0.305054)
			(stroke
				(width 0.1)
				(type default)
			)
			(layer "B.Fab")
		)
		(fp_line
			(start 0.12065 -0.305054)
			(end 0.12065 -0.2794)
			(stroke
				(width 0.1)
				(type default)
			)
			(layer "B.Fab")
		)
		(fp_line
			(start -0.12065 -0.3048)
			(end -0.67945 -0.3048)
			(stroke
				(width 0.1)
				(type default)
			)
			(layer "B.Fab")
		)
		(fp_line
			(start -0.67945 -0.3048)
			(end -0.67945 0.3048)
			(stroke
				(width 0.1)
				(type default)
			)
			(layer "B.Fab")
		)
		(fp_line
			(start 0.12065 -0.2794)
			(end -0.12065 -0.2794)
			(stroke
				(width 0.1)
				(type default)
			)
			(layer "B.Fab")
		)
		(fp_line
			(start -0.12065 -0.2794)
			(end -0.12065 -0.3048)
			(stroke
				(width 0.1)
				(type default)
			)
			(layer "B.Fab")
		)
		(fp_line
			(start 0.12065 0.2794)
			(end 0.12065 0.3048)
			(stroke
				(width 0.1)
				(type default)
			)
			(layer "B.Fab")
		)
		(fp_line
			(start -0.120396 0.2794)
			(end 0.12065 0.2794)
			(stroke
				(width 0.1)
				(type default)
			)
			(layer "B.Fab")
		)
		(fp_line
			(start 0.67945 0.3048)
			(end 0.67945 -0.305054)
			(stroke
				(width 0.1)
				(type default)
			)
			(layer "B.Fab")
		)
		(fp_line
			(start 0.12065 0.3048)
			(end 0.67945 0.3048)
			(stroke
				(width 0.1)
				(type default)
			)
			(layer "B.Fab")
		)
		(fp_line
			(start -0.120396 0.3048)
			(end -0.120396 0.2794)
			(stroke
				(width 0.1)
				(type default)
			)
			(layer "B.Fab")
		)
		(fp_line
			(start -0.67945 0.3048)
			(end -0.120396 0.3048)
			(stroke
				(width 0.1)
				(type default)
			)
			(layer "B.Fab")
		)
		(pad "1" smd circle
			(at 0.40005 0 270)
			(size 0 0)
			(layers "B.Cu" "B.Mask" "B.Paste")
			(net "P0V8_PEX0_VCC1")
		)
		(pad "2" smd circle
			(at -0.40005 0 270)
			(size 0 0)
			(layers "B.Cu" "B.Mask" "B.Paste")
			(net "P0V8_PEX0_EN1")
		)
	)
	(footprint ""
		(layer "B.Cu")
		(at 291.84981 -290.199826 90)
		(property "Reference" "C1739"
			(at 0 0 90)
			(layer "B.SilkS")
			(hide yes)
			(effects
				(font
					(size 1.27 1.27)
				)
				(justify mirror)
			)
		)
		(property "Value" ""
			(at 0 0 90)
			(layer "B.Fab")
			(effects
				(font
					(size 1.27 1.27)
				)
				(justify mirror)
			)
		)
		(duplicate_pad_numbers_are_jumpers no)
		(fp_line
			(start 0.299974 -0.150114)
			(end -0.299974 -0.150114)
			(stroke
				(width 0.1)
				(type default)
			)
			(layer "B.Fab")
		)
		(fp_line
			(start -0.299974 -0.150114)
			(end -0.299974 0.150114)
			(stroke
				(width 0.1)
				(type default)
			)
			(layer "B.Fab")
		)
		(fp_line
			(start 0.299974 0.150114)
			(end 0.299974 -0.150114)
			(stroke
				(width 0.1)
				(type default)
			)
			(layer "B.Fab")
		)
		(fp_line
			(start -0.299974 0.150114)
			(end 0.299974 0.150114)
			(stroke
				(width 0.1)
				(type default)
			)
			(layer "B.Fab")
		)
		(pad "1" smd rect
			(at 0.2667 0 270)
			(size 0.3048 0.381)
			(layers "B.Cu" "B.Mask" "B.Paste")
			(net "P0V8_SERDES_VDDA_PEX2")
		)
		(pad "2" smd rect
			(at -0.2667 0 270)
			(size 0.3048 0.381)
			(layers "B.Cu" "B.Mask" "B.Paste")
			(net "GND")
		)
	)
	(footprint ""
		(layer "B.Cu")
		(at 229.145084 -225.673412 180)
		(property "Reference" "R6820"
			(at 0 0 0)
			(layer "B.SilkS")
			(hide yes)
			(effects
				(font
					(size 1.27 1.27)
				)
				(justify mirror)
			)
		)
		(property "Value" ""
			(at 0 0 0)
			(layer "B.Fab")
			(effects
				(font
					(size 1.27 1.27)
				)
				(justify mirror)
			)
		)
		(duplicate_pad_numbers_are_jumpers no)
		(fp_line
			(start 0.7874 0.4064)
			(end 0.7874 -0.4064)
			(stroke
				(width 0.1524)
				(type default)
			)
			(layer "B.SilkS")
		)
		(fp_line
			(start 0.7874 -0.4064)
			(end -0.7874 -0.4064)
			(stroke
				(width 0.1524)
				(type default)
			)
			(layer "B.SilkS")
		)
		(fp_line
			(start -0.7874 0.4064)
			(end 0.7874 0.4064)
			(stroke
				(width 0.1524)
				(type default)
			)
			(layer "B.SilkS")
		)
		(fp_line
			(start -0.7874 -0.4064)
			(end -0.7874 0.4064)
			(stroke
				(width 0.1524)
				(type default)
			)
			(layer "B.SilkS")
		)
		(fp_line
			(start 0.67945 0.3048)
			(end 0.67945 -0.305054)
			(stroke
				(width 0.1)
				(type default)
			)
			(layer "B.Fab")
		)
		(fp_line
			(start 0.67945 -0.305054)
			(end 0.12065 -0.305054)
			(stroke
				(width 0.1)
				(type default)
			)
			(layer "B.Fab")
		)
		(fp_line
			(start 0.12065 0.3048)
			(end 0.67945 0.3048)
			(stroke
				(width 0.1)
				(type default)
			)
			(layer "B.Fab")
		)
		(fp_line
			(start 0.12065 0.2794)
			(end 0.12065 0.3048)
			(stroke
				(width 0.1)
				(type default)
			)
			(layer "B.Fab")
		)
		(fp_line
			(start 0.12065 -0.2794)
			(end -0.12065 -0.2794)
			(stroke
				(width 0.1)
				(type default)
			)
			(layer "B.Fab")
		)
		(fp_line
			(start 0.12065 -0.305054)
			(end 0.12065 -0.2794)
			(stroke
				(width 0.1)
				(type default)
			)
			(layer "B.Fab")
		)
		(fp_line
			(start -0.120396 0.3048)
			(end -0.120396 0.2794)
			(stroke
				(width 0.1)
				(type default)
			)
			(layer "B.Fab")
		)
		(fp_line
			(start -0.120396 0.2794)
			(end 0.12065 0.2794)
			(stroke
				(width 0.1)
				(type default)
			)
			(layer "B.Fab")
		)
		(fp_line
			(start -0.12065 -0.2794)
			(end -0.12065 -0.3048)
			(stroke
				(width 0.1)
				(type default)
			)
			(layer "B.Fab")
		)
		(fp_line
			(start -0.12065 -0.3048)
			(end -0.67945 -0.3048)
			(stroke
				(width 0.1)
				(type default)
			)
			(layer "B.Fab")
		)
		(fp_line
			(start -0.67945 0.3048)
			(end -0.120396 0.3048)
			(stroke
				(width 0.1)
				(type default)
			)
			(layer "B.Fab")
		)
		(fp_line
			(start -0.67945 -0.3048)
			(end -0.67945 0.3048)
			(stroke
				(width 0.1)
				(type default)
			)
			(layer "B.Fab")
		)
		(pad "1" smd circle
			(at 0.40005 0)
			(size 0 0)
			(layers "B.Cu" "B.Mask" "B.Paste")
			(net "GND")
		)
		(pad "2" smd circle
			(at -0.40005 0)
			(size 0 0)
			(layers "B.Cu" "B.Mask" "B.Paste")
			(net "BOARD_TYPE_0_ADC_R")
		)
	)
	(footprint ""
		(layer "B.Cu")
		(at 112.578642 -281.024838 90)
		(property "Reference" "PC63"
			(at 0 0 90)
			(layer "B.SilkS")
			(hide yes)
			(effects
				(font
					(size 1.27 1.27)
				)
				(justify mirror)
			)
		)
		(property "Value" ""
			(at 0 0 90)
			(layer "B.Fab")
			(effects
				(font
					(size 1.27 1.27)
				)
				(justify mirror)
			)
		)
		(duplicate_pad_numbers_are_jumpers no)
		(fp_line
			(start 1.524 -0.762)
			(end -1.524 -0.762)
			(stroke
				(width 0.1524)
				(type default)
			)
			(layer "B.SilkS")
		)
		(fp_line
			(start -1.524 -0.762)
			(end -1.524 0.762)
			(stroke
				(width 0.1524)
				(type default)
			)
			(layer "B.SilkS")
		)
		(fp_line
			(start 1.524 0.762)
			(end 1.524 -0.762)
			(stroke
				(width 0.1524)
				(type default)
			)
			(layer "B.SilkS")
		)
		(fp_line
			(start -1.524 0.762)
			(end 1.524 0.762)
			(stroke
				(width 0.1524)
				(type default)
			)
			(layer "B.SilkS")
		)
		(fp_line
			(start 1.1049 -0.724916)
			(end 1.1049 0.724916)
			(stroke
				(width 0.1)
				(type default)
			)
			(layer "B.Fab")
		)
		(fp_line
			(start -1.1049 -0.724916)
			(end 1.1049 -0.724916)
			(stroke
				(width 0.1)
				(type default)
			)
			(layer "B.Fab")
		)
		(fp_line
			(start 1.1049 0.724916)
			(end -1.1049 0.724916)
			(stroke
				(width 0.1)
				(type default)
			)
			(layer "B.Fab")
		)
		(fp_line
			(start -1.1049 0.724916)
			(end -1.1049 -0.724916)
			(stroke
				(width 0.1)
				(type default)
			)
			(layer "B.Fab")
		)
		(pad "1" smd rect
			(at 0.889 0 90)
			(size 1.016 1.27)
			(layers "B.Cu" "B.Mask" "B.Paste")
			(net "SW_P12V_P0V8_PEX0_FLT")
		)
		(pad "2" smd rect
			(at -0.889 0 90)
			(size 1.016 1.27)
			(layers "B.Cu" "B.Mask" "B.Paste")
			(net "GND")
		)
	)
	(footprint ""
		(layer "B.Cu")
		(at 160.549844 -295.89984)
		(property "Reference" "C3175"
			(at 0 0 0)
			(layer "B.SilkS")
			(hide yes)
			(effects
				(font
					(size 1.27 1.27)
				)
				(justify mirror)
			)
		)
		(property "Value" ""
			(at 0 0 0)
			(layer "B.Fab")
			(effects
				(font
					(size 1.27 1.27)
				)
				(justify mirror)
			)
		)
		(duplicate_pad_numbers_are_jumpers no)
		(fp_line
			(start -0.299974 -0.150114)
			(end -0.299974 0.150114)
			(stroke
				(width 0.1)
				(type default)
			)
			(layer "B.Fab")
		)
		(fp_line
			(start -0.299974 0.150114)
			(end 0.299974 0.150114)
			(stroke
				(width 0.1)
				(type default)
			)
			(layer "B.Fab")
		)
		(fp_line
			(start 0.299974 -0.150114)
			(end -0.299974 -0.150114)
			(stroke
				(width 0.1)
				(type default)
			)
			(layer "B.Fab")
		)
		(fp_line
			(start 0.299974 0.150114)
			(end 0.299974 -0.150114)
			(stroke
				(width 0.1)
				(type default)
			)
			(layer "B.Fab")
		)
		(pad "1" smd rect
			(at 0.2667 0 180)
			(size 0.3048 0.381)
			(layers "B.Cu" "B.Mask" "B.Paste")
			(net "P1V8_PEX")
		)
		(pad "2" smd rect
			(at -0.2667 0 180)
			(size 0.3048 0.381)
			(layers "B.Cu" "B.Mask" "B.Paste")
			(net "GND")
		)
	)
)
